# TIMECARD (Time Appliance Project (Time Card)) — schematic netlist excerpt (pin names and nets, part order shuffled) for the footprints in the layout excerpt that follows; sources: Cadence DE-HDL packaged netlist, KiCad conversion of R4006-B0001-02_R01.brd

C173  CAPACITOR  47UF 4V 20%  pkg SMC_0805R_H057  page 14 : \1\ = XP1R0V_FPGA_VCCINT ; \2\ = SG
R78  RESISTOR  33OHM 1%  pkg SMC_0402R_H016  page 20 : \1\ = R_BNO080_RST_N ; \2\ = FPGA_OUT_BNO080_RST_N

(kicad_pcb
	(version 20260206)
	(generator "pcbnew")
	(generator_version "10.0")
	(general
		(thickness 1.6)
		(legacy_teardrops no)
	)
	(paper "A4")
	(title_block
		(title "timecard-production-celestica-r4006 — R4006-B0001-02_R01.brd")
		(comment 1 "Time Appliance Project (Time Card) / footprints 183-184 of 1113")
	)
	(layers
		(0 "F.Cu" signal "TOP")
		(4 "In1.Cu" signal "L02_GND1")
		(6 "In2.Cu" signal "L03_SIG1")
		(8 "In3.Cu" signal "L04_GND2")
		(10 "In4.Cu" signal "L05_VCC1")
		(12 "In5.Cu" signal "L06_VCC2")
		(14 "In6.Cu" signal "L07_GND3")
		(16 "In7.Cu" signal "L08_SIG2")
		(18 "In8.Cu" signal "L09_GND4")
		(2 "B.Cu" signal "BOTTOM")
		(9 "F.Adhes" user "F.Adhesive")
		(11 "B.Adhes" user "B.Adhesive")
		(13 "F.Paste" user "Package Geometry/Pastemask Top")
		(15 "B.Paste" user "Package Geometry/Pastemask Bottom")
		(5 "F.SilkS" user "Ref Des/Silkscreen Top")
		(7 "B.SilkS" user "Ref Des/Silkscreen Bottom")
		(1 "F.Mask" user "Board Geometry/Soldermask Top")
		(3 "B.Mask" user "Board Geometry/Soldermask Bottom")
		(17 "Dwgs.User" user "User.Drawings")
		(19 "Cmts.User" user "User.Comments")
		(21 "Eco1.User" user "User.Eco1")
		(23 "Eco2.User" user "User.Eco2")
		(25 "Edge.Cuts" user "Board Geometry/Outline")
		(27 "Margin" user)
		(31 "F.CrtYd" user "Package Geometry/Place Bound Top")
		(29 "B.CrtYd" user "Package Geometry/Place Bound Bottom")
		(35 "F.Fab" user "Ref Des/Assembly Top")
		(33 "B.Fab" user "Ref Des/Assembly Bottom")
	)
	(footprint ""
		(layer "F.Cu")
		(at 80.772 -58.3946 180)
		(property "Reference" "R78"
			(at 10.668 19.39163 0)
			(unlocked yes)
			(layer "F.SilkS")
			(effects
				(font
					(size 0.7874 0.5842)
					(thickness 0.1524)
				)
			)
		)
		(property "Value" "VAL*"
			(at 0.02032 2.13233 180)
			(unlocked yes)
			(layer "F.Fab")
			(hide yes)
			(effects
				(font
					(size 0.7874 0.5842)
					(thickness 0.1524)
				)
			)
		)
		(property "Tolerance" "TOL*"
			(at 0.044704 3.05435 180)
			(unlocked yes)
			(layer "Cmts.User")
			(hide yes)
			(effects
				(font
					(size 0.7874 0.5842)
					(thickness 0.1524)
				)
			)
		)
		(property "User Part Number" "PARTNUM*"
			(at 0.02032 4.024884 180)
			(unlocked yes)
			(layer "Cmts.User")
			(hide yes)
			(effects
				(font
					(size 0.7874 0.5842)
					(thickness 0.1524)
				)
			)
		)
		(property "Device Type" "RESISTOR-G155-133R0-01,33OHM,1%"
			(at 0.008382 1.210564 180)
			(unlocked yes)
			(layer "F.Fab")
			(hide yes)
			(effects
				(font
					(size 0.7874 0.5842)
					(thickness 0.1524)
				)
			)
		)
		(duplicate_pad_numbers_are_jumpers no)
		(fp_line
			(start 1.143 0.5588)
			(end 1.143 -0.5588)
			(stroke
				(width 0.1)
				(type default)
			)
			(layer "F.SilkS")
		)
		(fp_line
			(start 1.143 -0.5588)
			(end -1.143 -0.5588)
			(stroke
				(width 0.1)
				(type default)
			)
			(layer "F.SilkS")
		)
		(fp_line
			(start -1.143 0.5588)
			(end 1.143 0.5588)
			(stroke
				(width 0.1)
				(type default)
			)
			(layer "F.SilkS")
		)
		(fp_line
			(start -1.143 -0.5588)
			(end -1.143 0.5588)
			(stroke
				(width 0.1)
				(type default)
			)
			(layer "F.SilkS")
		)
		(fp_rect
			(start 1.143 -0.5588)
			(end -1.143 0.5588)
			(stroke
				(width 0)
				(type default)
			)
			(fill no)
			(layer "F.CrtYd")
		)
		(fp_line
			(start 0.508 0.3048)
			(end 0.508 -0.3048)
			(stroke
				(width 0.1)
				(type default)
			)
			(layer "F.Fab")
		)
		(fp_line
			(start 0.508 -0.3048)
			(end -0.508 -0.3048)
			(stroke
				(width 0.1)
				(type default)
			)
			(layer "F.Fab")
		)
		(fp_line
			(start -0.508 0.3048)
			(end 0.508 0.3048)
			(stroke
				(width 0.1)
				(type default)
			)
			(layer "F.Fab")
		)
		(fp_line
			(start -0.508 -0.3048)
			(end -0.508 0.3048)
			(stroke
				(width 0.1)
				(type default)
			)
			(layer "F.Fab")
		)
		(pad "1" smd rect
			(at -0.5334 0 180)
			(size 0.7112 0.6096)
			(layers "F.Cu" "F.Mask" "F.Paste")
			(net "R_BNO080_RST_N")
		)
		(pad "2" smd rect
			(at 0.5334 0 180)
			(size 0.7112 0.6096)
			(layers "F.Cu" "F.Mask" "F.Paste")
			(net "FPGA_OUT_BNO080_RST_N")
		)
		(zone
			(layer "F.Cu")
			(hatch none 0.5)
			(connect_pads
				(clearance 0)
			)
			(min_thickness 0.25)
			(keepout
				(tracks allowed)
				(vias not_allowed)
				(pads allowed)
				(copperpour not_allowed)
				(footprints allowed)
			)
			(placement
				(enabled no)
				(sheetname "")
			)
			(fill
				(thermal_gap 0.5)
				(thermal_bridge_width 0.5)
				(island_removal_mode 0)
			)
			(polygon
				(pts
					(xy 80.6958 -58.0898) (xy 80.8482 -58.0898) (xy 80.8482 -58.6994) (xy 80.6958 -58.6994)
				)
			)
		)
	)
	(footprint ""
		(layer "F.Cu")
		(at 133.096 -31.496)
		(property "Reference" "C173"
			(at 4.572 0.29337 0)
			(unlocked yes)
			(layer "F.SilkS")
			(effects
				(font
					(size 0.7874 0.5842)
					(thickness 0.1524)
				)
			)
		)
		(property "Value" "VAL*"
			(at 0.0762 3.134106 0)
			(unlocked yes)
			(layer "F.Fab")
			(hide yes)
			(effects
				(font
					(size 0.7874 0.5842)
					(thickness 0.1524)
				)
			)
		)
		(property "Tolerance" "TOL*"
			(at 0.0762 4.048506 0)
			(unlocked yes)
			(layer "Cmts.User")
			(hide yes)
			(effects
				(font
					(size 0.7874 0.5842)
					(thickness 0.1524)
				)
			)
		)
		(property "User Part Number" "PARTNUM*"
			(at 0.1016 5.013706 0)
			(unlocked yes)
			(layer "Cmts.User")
			(hide yes)
			(effects
				(font
					(size 0.7874 0.5842)
					(thickness 0.1524)
				)
			)
		)
		(property "Device Type" "CAPACITOR-G107-0F476-AM,47UF,2A"
			(at 0.0508 2.194306 0)
			(unlocked yes)
			(layer "F.Fab")
			(hide yes)
			(effects
				(font
					(size 0.7874 0.5842)
					(thickness 0.1524)
				)
			)
		)
		(duplicate_pad_numbers_are_jumpers no)
		(fp_line
			(start -1.5748 -0.9398)
			(end -1.5748 0.9398)
			(stroke
				(width 0.1)
				(type default)
			)
			(layer "F.SilkS")
		)
		(fp_line
			(start -1.5748 0.9398)
			(end 1.5748 0.9398)
			(stroke
				(width 0.1)
				(type default)
			)
			(layer "F.SilkS")
		)
		(fp_line
			(start 1.5748 -0.9398)
			(end -1.5748 -0.9398)
			(stroke
				(width 0.1)
				(type default)
			)
			(layer "F.SilkS")
		)
		(fp_line
			(start 1.5748 0.9398)
			(end 1.5748 -0.9398)
			(stroke
				(width 0.1)
				(type default)
			)
			(layer "F.SilkS")
		)
		(fp_rect
			(start 1.5748 -0.9398)
			(end -1.5748 0.9398)
			(stroke
				(width 0)
				(type default)
			)
			(fill no)
			(layer "F.CrtYd")
		)
		(fp_line
			(start -1.016 -0.635)
			(end -1.016 0.635)
			(stroke
				(width 0.1)
				(type default)
			)
			(layer "F.Fab")
		)
		(fp_line
			(start -1.016 0.635)
			(end 1.016 0.635)
			(stroke
				(width 0.1)
				(type default)
			)
			(layer "F.Fab")
		)
		(fp_line
			(start 1.016 -0.635)
			(end -1.016 -0.635)
			(stroke
				(width 0.1)
				(type default)
			)
			(layer "F.Fab")
		)
		(fp_line
			(start 1.016 0.635)
			(end 1.016 -0.635)
			(stroke
				(width 0.1)
				(type default)
			)
			(layer "F.Fab")
		)
		(pad "1" smd rect
			(at -0.8382 0)
			(size 0.9652 1.3716)
			(layers "F.Cu" "F.Mask" "F.Paste")
			(net "XP1R0V_FPGA_VCCINT")
		)
		(pad "2" smd rect
			(at 0.8382 0)
			(size 0.9652 1.3716)
			(layers "F.Cu" "F.Mask" "F.Paste")
			(net "SG")
		)
		(zone
			(layer "F.Cu")
			(hatch none 0.5)
			(connect_pads
				(clearance 0)
			)
			(min_thickness 0.25)
			(keepout
				(tracks allowed)
				(vias not_allowed)
				(pads allowed)
				(copperpour not_allowed)
				(footprints allowed)
			)
			(placement
				(enabled no)
				(sheetname "")
			)
			(fill
				(thermal_gap 0.5)
				(thermal_bridge_width 0.5)
				(island_removal_mode 0)
			)
			(polygon
				(pts
					(xy 133.3246 -32.131) (xy 132.8674 -32.131) (xy 132.8674 -30.861) (xy 133.3246 -30.861)
				)
			)
		)
	)
)
